# S9S_MB_2U (Grand Teton) — schematic parts with pin connectivity, parts 1625–1625 of 6093; source: Cadence DE-HDL packaged netlist (pstxprt.dat, pstxnet.dat, pstchip.dat)

J32  SCONN288_ADR50017P087CC  SCONN288_ADR50017-P087CC IO  pkg DDR288S_1-1VXB  page 113
  1  VIN_BULK0  POWER  = P12V_S3_AUX_CPU1_NVDIMM
  2  RFU0  TRI  = TP_CHH_CPU1_DIMM2_FRU_0
  3  VIN_MGMT  POWER  = P3V3_AUX
  4  HSCL  IN  = I3C_SPD_DDREFGH_CPU1_LVC1_SCL_7
  5  HSDA  BI  = I3C_SPD_DDREFGH_CPU1_LVC1_SDA
  6  VSS0  POWER  = GND
  7  DQ0_A  BI  = M_H_CPU1_SA_DQ<0>
  8  VSS1  POWER  = GND
  9  DQ1_A  BI  = M_H_CPU1_SA_DQ<1>
  10  VSS2  POWER  = GND
  11  DQS0_A_T  BI  = M_H_CPU1_SA_DQS_DP<0>
  12  DQS0_A_C  BI  = M_H_CPU1_SA_DQS_DN<0>
  13  VSS3  POWER  = GND
  14  DQ4_A  BI  = M_H_CPU1_SA_DQ<4>
  15  VSS4  POWER  = GND
  16  DQ5_A  BI  = M_H_CPU1_SA_DQ<5>
  17  VSS5  POWER  = GND
  18  DQ8_A  BI  = M_H_CPU1_SA_DQ<8>
  19  VSS6  POWER  = GND
  20  DQ9_A  BI  = M_H_CPU1_SA_DQ<9>
  21  VSS7  POWER  = GND
  22  DQS1_A_T  BI  = M_H_CPU1_SA_DQS_DP<1>
  23  DQS1_A_C  BI  = M_H_CPU1_SA_DQS_DN<1>
  24  VSS8  POWER  = GND
  25  DQ12_A  BI  = M_H_CPU1_SA_DQ<12>
  26  VSS9  POWER  = GND
  27  DQ13_A  BI  = M_H_CPU1_SA_DQ<13>
  28  VSS10  POWER  = GND
  29  DQ16_A  BI  = M_H_CPU1_SA_DQ<16>
  30  VSS11  POWER  = GND
  31  DQ17_A  BI  = M_H_CPU1_SA_DQ<17>
  32  VSS12  POWER  = GND
  33  DQS2_A_T  BI  = M_H_CPU1_SA_DQS_DP<2>
  34  DQS2_A_C  BI  = M_H_CPU1_SA_DQS_DN<2>
  35  VSS13  POWER  = GND
  36  DQ20_A  BI  = M_H_CPU1_SA_DQ<20>
  37  VSS14  POWER  = GND
  38  DQ21_A  BI  = M_H_CPU1_SA_DQ<21>
  39  VSS15  POWER  = GND
  40  DQ24_A  BI  = M_H_CPU1_SA_DQ<24>
  41  VSS16  POWER  = GND
  42  DQ25_A  BI  = M_H_CPU1_SA_DQ<25>
  43  VSS17  POWER  = GND
  44  DQS3_A_T  BI  = M_H_CPU1_SA_DQS_DP<3>
  45  DQS3_A_C  BI  = M_H_CPU1_SA_DQS_DN<3>
  46  VSS18  POWER  = GND
  47  DQ28_A  BI  = M_H_CPU1_SA_DQ<28>
  48  VSS19  POWER  = GND
  49  DQ29_A  BI  = M_H_CPU1_SA_DQ<29>
  50  VSS20  POWER  = GND
  51  CB0_A  BI  = M_H_CPU1_SA_CB<0>
  52  VSS21  POWER  = GND
  53  CB1_A  BI  = M_H_CPU1_SA_CB<1>
  54  VSS22  POWER  = GND
  55  DQS4_A_T  BI  = M_H_CPU1_SA_DQS_DP<4>
  56  DQS4_A_C  BI  = M_H_CPU1_SA_DQS_DN<4>
  57  VSS23  POWER  = GND
  58  CB4_A  BI  = M_H_CPU1_SA_CB<4>
  59  VSS24  POWER  = GND
  60  CB5_A  BI  = M_H_CPU1_SA_CB<5>
  61  VSS25  POWER  = GND
  62  ALERT_N  OUT  = M_H_CPU1_ALERT_N
  63  VSS26  POWER  = GND
  64  CS0_A_N  IN  = M_H_CPU1_SA_CS_N<2>
  65  VSS27  POWER  = GND
  66  CA0_A  IN  = M_H_CPU1_SA_CA<0>
  67  VSS28  POWER  = GND
  68  CA2_A  IN  = M_H_CPU1_SA_CA<2>
  69  VSS29  POWER  = GND
  70  CA4_A  IN  = M_H_CPU1_SA_CA<4>
  71  VSS30  POWER  = GND
  72  CA6_A  IN  = M_H_CPU1_SA_CA<6>
  73  VSS31  POWER  = GND
  74  PAR_A  IN  = M_H_CPU1_SA_PAR
  75  VSS32  POWER  = GND
  76  CA0_B  IN  = M_H_CPU1_SB_CA<0>
  77  VSS33  POWER  = GND
  78  CA2_B  IN  = M_H_CPU1_SB_CA<2>
  79  VSS34  POWER  = GND
  80  CA4_B  IN  = M_H_CPU1_SB_CA<4>
  81  VSS35  POWER  = GND
  82  CA6_B  IN  = M_H_CPU1_SB_CA<6>
  83  VSS36  POWER  = GND
  84  CS0_B_N  IN  = M_H_CPU1_SB_CS_N<2>
  85  VSS37  POWER  = GND
  86  \lbd||rsp_a_n\  OUT  = M_H_CPU1_SA_RSP<1>
  87  \lbs||rsp_b_n\  OUT  = M_H_CPU1_SB_RSP<1>
  88  VSS38  POWER  = GND
  89  CB4_B  BI  = M_H_CPU1_SB_CB<4>
  90  VSS39  POWER  = GND
  91  CB5_B  BI  = M_H_CPU1_SB_CB<5>
  92  VSS40  POWER  = GND
  93  \dqs9_b_t||tdqs9_b_t||dbi4_b_n\  BI  = M_H_CPU1_SB_DQS_DP<9>
  94  \dqs9_b_c||tdqs9_b_c\  BI  = M_H_CPU1_SB_DQS_DN<9>
  95  VSS41  POWER  = GND
  96  CB0_B  BI  = M_H_CPU1_SB_CB<0>
  97  VSS42  POWER  = GND
  98  CB1_B  BI  = M_H_CPU1_SB_CB<1>
  99  VSS43  POWER  = GND
  100  DQ0_B  BI  = M_H_CPU1_SB_DQ<0>
  101  VSS44  POWER  = GND
  102  DQ1_B  BI  = M_H_CPU1_SB_DQ<1>
  103  VSS45  POWER  = GND
  104  DQS0_B_T  BI  = M_H_CPU1_SB_DQS_DP<0>
  105  DQS0_B_C  BI  = M_H_CPU1_SB_DQS_DN<0>
  106  VSS46  POWER  = GND
  107  DQ4_B  BI  = M_H_CPU1_SB_DQ<4>
  108  VSS47  POWER  = GND
  109  DQ5_B  BI  = M_H_CPU1_SB_DQ<5>
  110  VSS48  POWER  = GND
  111  DQ8_B  BI  = M_H_CPU1_SB_DQ<8>
  112  VSS49  POWER  = GND
  113  DQ9_B  BI  = M_H_CPU1_SB_DQ<9>
  114  VSS50  POWER  = GND
  115  DQS1_B_T  BI  = M_H_CPU1_SB_DQS_DP<1>
  116  DQS1_B_C  BI  = M_H_CPU1_SB_DQS_DN<1>
  117  VSS51  POWER  = GND
  118  DQ12_B  BI  = M_H_CPU1_SB_DQ<12>
  119  VSS52  POWER  = GND
  120  DQ13_B  BI  = M_H_CPU1_SB_DQ<13>
  121  VSS53  POWER  = GND
  122  DQ16_B  BI  = M_H_CPU1_SB_DQ<16>
  123  VSS54  POWER  = GND
  124  DQ17_B  BI  = M_H_CPU1_SB_DQ<17>
  125  VSS55  POWER  = GND
  126  DQS2_B_T  BI  = M_H_CPU1_SB_DQS_DP<2>
  127  DQS2_B_C  BI  = M_H_CPU1_SB_DQS_DN<2>
  128  VSS56  POWER  = GND
  129  DQ20_B  BI  = M_H_CPU1_SB_DQ<20>
  130  VSS57  POWER  = GND
  131  DQ21_B  BI  = M_H_CPU1_SB_DQ<21>
  132  VSS58  POWER  = GND
  133  DQ24_B  BI  = M_H_CPU1_SB_DQ<24>
  134  VSS59  POWER  = GND
  135  DQ25_B  BI  = M_H_CPU1_SB_DQ<25>
  136  VSS60  POWER  = GND
  137  DQS3_B_T  BI  = M_H_CPU1_SB_DQS_DP<3>
  138  DQS3_B_C  BI  = M_H_CPU1_SB_DQS_DN<3>
  139  VSS61  POWER  = GND
  140  DQ28_B  BI  = M_H_CPU1_SB_DQ<28>
  141  VSS62  POWER  = GND
  142  DQ29_B  BI  = M_H_CPU1_SB_DQ<29>
  143  VSS63  POWER  = GND
  144  RFU1  TRI  = TP_CHH_CPU1_DIMM2_FRU_1
  145  VIN_BULK1  POWER  = P12V_S3_AUX_CPU1_NVDIMM
  146  VIN_BULK2  POWER  = P12V_S3_AUX_CPU1_NVDIMM
  147  \pwr_good||fail_n\  BI  = PWRGD_CHH_CPU1_DIMM2
  148  HSA  IN  = PD_CHH_CPU1_DIMM2_SAA
  149  RFU2  TRI  = TP_CHH_CPU1_DIMM2_FRU_2
  150  RFU3  TRI  = TP_CHH_CPU1_DIMM2_FRU_3
  151  VSS64  POWER  = GND
  152  DQ2_A  BI  = M_H_CPU1_SA_DQ<2>
  153  VSS65  POWER  = GND
  154  DQ3_A  BI  = M_H_CPU1_SA_DQ<3>
  155  VSS66  POWER  = GND
  156  \dqs5_a_c||tdqs5_a_c||dqs5_a_t||tdqs5_a_t\  BI  = M_H_CPU1_SA_DQS_DN<5>
  157  \dqs5_a_t||tdqs5_a_t\  BI  = M_H_CPU1_SA_DQS_DP<5>
  158  VSS67  POWER  = GND
  159  DQ6_A  BI  = M_H_CPU1_SA_DQ<6>
  160  VSS68  POWER  = GND
  161  DQ7_A  BI  = M_H_CPU1_SA_DQ<7>
  162  VSS69  POWER  = GND
  163  DQ10_A  BI  = M_H_CPU1_SA_DQ<10>
  164  VSS70  POWER  = GND
  165  DQ11_A  BI  = M_H_CPU1_SA_DQ<11>
  166  VSS71  POWER  = GND
  167  \dqs6_a_c||tdqs6_a_c||dqs6_a_t||tdqs6_a_t\  BI  = M_H_CPU1_SA_DQS_DN<6>
  168  \dqs6_a_t||tdqs6_a_t\  BI  = M_H_CPU1_SA_DQS_DP<6>
  169  VSS72  POWER  = GND
  170  DQ14_A  BI  = M_H_CPU1_SA_DQ<14>
  171  VSS73  POWER  = GND
  172  DQ15_A  BI  = M_H_CPU1_SA_DQ<15>
  173  VSS74  POWER  = GND
  174  DQ18_A  BI  = M_H_CPU1_SA_DQ<18>
  175  VSS75  POWER  = GND
  176  DQ19_A  BI  = M_H_CPU1_SA_DQ<19>
  177  VSS76  POWER  = GND
  178  \dqs7_a_c||tdqs7_a_c\  BI  = M_H_CPU1_SA_DQS_DN<7>
  179  \dqs7_a_t||tdqs7_a_t\  BI  = M_H_CPU1_SA_DQS_DP<7>
  180  VSS77  POWER  = GND
  181  DQ22_A  BI  = M_H_CPU1_SA_DQ<22>
  182  VSS78  POWER  = GND
  183  DQ23_A  BI  = M_H_CPU1_SA_DQ<23>
  184  VSS79  POWER  = GND
  185  DQ26_A  BI  = M_H_CPU1_SA_DQ<26>
  186  VSS80  POWER  = GND
  187  DQ27_A  BI  = M_H_CPU1_SA_DQ<27>
  188  VSS81  POWER  = GND
  189  \dqs8_a_c||tdqs8_a_c\  BI  = M_H_CPU1_SA_DQS_DN<8>
  190  \dqs8_a_t||tdqs8_a_t\  BI  = M_H_CPU1_SA_DQS_DP<8>
  191  VSS82  POWER  = GND
  192  DQ30_A  BI  = M_H_CPU1_SA_DQ<30>
  193  VSS83  POWER  = GND
  194  DQ31_A  BI  = M_H_CPU1_SA_DQ<31>
  195  VSS84  POWER  = GND
  196  CB2_A  BI  = M_H_CPU1_SA_CB<2>
  197  VSS85  POWER  = GND
  198  CB3_A  BI  = M_H_CPU1_SA_CB<3>
  199  VSS86  POWER  = GND
  200  \dqs9_a_c||tdqs9_a_c\  BI  = M_H_CPU1_SA_DQS_DN<9>
  201  \dqs9_a_t||tdqs9_a_t\  BI  = M_H_CPU1_SA_DQS_DP<9>
  202  VSS87  POWER  = GND
  203  CB6_A  BI  = M_H_CPU1_SA_CB<6>
  204  VSS88  POWER  = GND
  205  CB7_A  BI  = M_H_CPU1_SA_CB<7>
  206  VSS89  POWER  = GND
  207  RESET_N  IN  = RST_M_GH_CPU1_FPGA_N
  208  VSS90  POWER  = GND
  209  CS1_A_N  IN  = M_H_CPU1_SA_CS_N<3>
  210  VSS91  POWER  = GND
  211  CA1_A  IN  = M_H_CPU1_SA_CA<1>
  212  VSS92  POWER  = GND
  213  CA3_A  IN  = M_H_CPU1_SA_CA<3>
  214  VSS93  POWER  = GND
  215  CA5_A  IN  = M_H_CPU1_SA_CA<5>
  216  VSS94  POWER  = GND
  217  CK_T  IN  = M_H_CPU1_CLK_DP<1>
  218  CK_C  IN  = M_H_CPU1_CLK_DN<1>
  219  VSS95  POWER  = GND
  220  RFU4  TRI  = TP_CHH_CPU1_DIMM2_FRU_4
  221  CA1_B  IN  = M_H_CPU1_SB_CA<1>
  222  VSS96  POWER  = GND
  223  CA3_B  IN  = M_H_CPU1_SB_CA<3>
  224  VSS97  POWER  = GND
  225  CA5_B  IN  = M_H_CPU1_SB_CA<5>
  226  VSS98  POWER  = GND
  227  PAR_B  IN  = M_H_CPU1_SB_PAR
  228  VSS99  POWER  = GND
  229  CS1_B_N  IN  = M_H_CPU1_SB_CS_N<3>
  230  VSS100  POWER  = GND
  231  RFU5  TRI  = TP_CHH_CPU1_DIMM2_FRU_5
  232  RFU6  TRI  = TP_CHH_CPU1_DIMM2_FRU_6
  233  VSS101  POWER  = GND
  234  CB6_B  BI  = M_H_CPU1_SB_CB<6>
  235  VSS102  POWER  = GND
  236  CB7_B  BI  = M_H_CPU1_SB_CB<7>
  237  VSS103  POWER  = GND
  238  DQS4_B_C  BI  = M_H_CPU1_SB_DQS_DN<4>
  239  DQS4_B_T  BI  = M_H_CPU1_SB_DQS_DP<4>
  240  VSS104  POWER  = GND
  241  CB2_B  BI  = M_H_CPU1_SB_CB<2>
  242  VSS105  POWER  = GND
  243  CB3_B  BI  = M_H_CPU1_SB_CB<3>
  244  VSS106  POWER  = GND
  245  DQ2_B  BI  = M_H_CPU1_SB_DQ<2>
  246  VSS107  POWER  = GND
  247  DQ3_B  BI  = M_H_CPU1_SB_DQ<3>
  248  VSS108  POWER  = GND
  249  \dqs5_b_c||tdqs5_b_c\  BI  = M_H_CPU1_SB_DQS_DN<5>
  250  \dqs5_b_t||tdqs5_b_t\  BI  = M_H_CPU1_SB_DQS_DP<5>
  251  VSS109  POWER  = GND
  252  DQ6_B  BI  = M_H_CPU1_SB_DQ<6>
  253  VSS110  POWER  = GND
  254  DQ7_B  BI  = M_H_CPU1_SB_DQ<7>
  255  VSS111  POWER  = GND
  256  DQ10_B  BI  = M_H_CPU1_SB_DQ<10>
  257  VSS112  POWER  = GND
  258  DQ11_B  BI  = M_H_CPU1_SB_DQ<11>
  259  VSS113  POWER  = GND
  260  \dqs6_b_c||tdqs6_b_c\  BI  = M_H_CPU1_SB_DQS_DN<6>
  261  \dqs6_b_t||tdqs6_b_t\  BI  = M_H_CPU1_SB_DQS_DP<6>
  262  VSS114  POWER  = GND
  263  DQ14_B  BI  = M_H_CPU1_SB_DQ<14>
  264  VSS115  POWER  = GND
  265  DQ15_B  BI  = M_H_CPU1_SB_DQ<15>
  266  VSS116  POWER  = GND
  267  DQ18_B  BI  = M_H_CPU1_SB_DQ<18>
  268  VSS117  POWER  = GND
  269  DQ19_B  BI  = M_H_CPU1_SB_DQ<19>
  270  VSS118  POWER  = GND
  271  \dqs7_b_c||tdqs7_b_c\  BI  = M_H_CPU1_SB_DQS_DN<7>
  272  \dqs7_b_t||tdqs7_b_t\  BI  = M_H_CPU1_SB_DQS_DP<7>
  273  VSS119  POWER  = GND
  274  DQ22_B  BI  = M_H_CPU1_SB_DQ<22>
  275  VSS120  POWER  = GND
  276  DQ23_B  BI  = M_H_CPU1_SB_DQ<23>
  277  VSS121  POWER  = GND
  278  DQ26_B  BI  = M_H_CPU1_SB_DQ<26>
  279  VSS122  POWER  = GND
  280  DQ27_B  BI  = M_H_CPU1_SB_DQ<27>
  281  VSS123  POWER  = GND
  282  \dqs8_b_c||tdqs8_b_c\  BI  = M_H_CPU1_SB_DQS_DN<8>
  283  \dqs8_b_t||tdqs8_b_t\  BI  = M_H_CPU1_SB_DQS_DP<8>
  284  VSS124  POWER  = GND
  285  DQ30_B  BI  = M_H_CPU1_SB_DQ<30>
  286  VSS125  POWER  = GND
  287  DQ31_B  BI  = M_H_CPU1_SB_DQ<31>
  288  VSS126  POWER  = GND
  G1  G1  POWER  = GND
  G2  G2  POWER  = GND
  G3  G3  POWER  = GND
